# T6G (Grand Teton) — schematic netlist excerpt (pin names and nets, part order shuffled) for the footprints in the layout excerpt that follows; sources: Cadence DE-HDL packaged netlist, KiCad conversion of 04192023_DAF0TMB3IC0_F0TG_MB_C_brd_V02_OCP.brd

Q27  BSS138DW7F  BSS138DW-7-F IC  pkg SOT363A  page 188
  S1  = GND
  G1  = PWRGD_P3V3_EN
  D2  = PWRGD_P3V3_R1
  S2  = GND
  G2  = PWRGD_P3V3_EN_N
  D1  = PWRGD_P3V3_EN_N

PR76  Q_RES  1 1% CHIP  pkg 0402LF  page 200 : A = PVDDCR_CPU1_P0_VCC ; B = P3V3_AUX

(kicad_pcb
	(version 20260206)
	(generator "pcbnew")
	(generator_version "10.0")
	(general
		(thickness 1.6)
		(legacy_teardrops no)
	)
	(paper "A4")
	(title_block
		(title "04192023_DAF0TMB3IC0_F0TG_MB_C_brd_V02_OCP.brd")
		(comment 1 "Grand Teton / footprints 487-489 of 8354")
	)
	(layers
		(0 "F.Cu" signal "TOP")
		(4 "In1.Cu" signal "GND")
		(6 "In2.Cu" signal "IN1")
		(8 "In3.Cu" signal "GND1")
		(10 "In4.Cu" signal "IN2")
		(12 "In5.Cu" signal "GND2")
		(14 "In6.Cu" signal "IN3")
		(16 "In7.Cu" signal "GND3")
		(18 "In8.Cu" signal "VCC")
		(20 "In9.Cu" signal "VCC1")
		(22 "In10.Cu" signal "GND4")
		(24 "In11.Cu" signal "IN4")
		(26 "In12.Cu" signal "GND5")
		(28 "In13.Cu" signal "IN5")
		(30 "In14.Cu" signal "GND6")
		(32 "In15.Cu" signal "IN6")
		(34 "In16.Cu" signal "GND7")
		(2 "B.Cu" signal "BOTTOM")
		(9 "F.Adhes" user "F.Adhesive")
		(11 "B.Adhes" user "B.Adhesive")
		(13 "F.Paste" user "Package Geometry/Pastemask Top")
		(15 "B.Paste" user "Package Geometry/Pastemask Bottom")
		(5 "F.SilkS" user "Ref Des/Silkscreen Top")
		(7 "B.SilkS" user "Ref Des/Silkscreen Bottom")
		(1 "F.Mask" user "Board Geometry/Soldermask Top")
		(3 "B.Mask" user "Board Geometry/Soldermask Bottom")
		(17 "Dwgs.User" user "User.Drawings")
		(19 "Cmts.User" user "User.Comments")
		(21 "Eco1.User" user "User.Eco1")
		(23 "Eco2.User" user "User.Eco2")
		(25 "Edge.Cuts" user "Board Geometry/Outline")
		(27 "Margin" user)
		(31 "F.CrtYd" user "Package Geometry/Place Bound Top")
		(29 "B.CrtYd" user "Package Geometry/Place Bound Bottom")
		(35 "F.Fab" user "Ref Des/Assembly Top")
		(33 "B.Fab" user "Ref Des/Assembly Bottom")
	)
	(footprint ""
		(layer "F.Cu")
		(at 318.262 -364.617 90)
		(property "Reference" "PR76"
			(at 0 0 90)
			(layer "F.SilkS")
			(hide yes)
			(effects
				(font
					(size 1.27 1.27)
				)
			)
		)
		(property "Value" ""
			(at 0 0 90)
			(layer "F.Fab")
			(effects
				(font
					(size 1.27 1.27)
				)
			)
		)
		(duplicate_pad_numbers_are_jumpers no)
		(fp_line
			(start 0.7874 -0.4064)
			(end 0.7874 0.4064)
			(stroke
				(width 0.1524)
				(type default)
			)
			(layer "F.SilkS")
		)
		(fp_line
			(start -0.7874 -0.4064)
			(end 0.7874 -0.4064)
			(stroke
				(width 0.1524)
				(type default)
			)
			(layer "F.SilkS")
		)
		(fp_line
			(start 0.7874 0.4064)
			(end -0.7874 0.4064)
			(stroke
				(width 0.1524)
				(type default)
			)
			(layer "F.SilkS")
		)
		(fp_line
			(start -0.7874 0.4064)
			(end -0.7874 -0.4064)
			(stroke
				(width 0.1524)
				(type default)
			)
			(layer "F.SilkS")
		)
		(fp_line
			(start -0.12065 -0.305054)
			(end -0.12065 -0.2794)
			(stroke
				(width 0.1)
				(type default)
			)
			(layer "F.Fab")
		)
		(fp_line
			(start -0.67945 -0.305054)
			(end -0.12065 -0.305054)
			(stroke
				(width 0.1)
				(type default)
			)
			(layer "F.Fab")
		)
		(fp_line
			(start 0.67945 -0.3048)
			(end 0.67945 0.3048)
			(stroke
				(width 0.1)
				(type default)
			)
			(layer "F.Fab")
		)
		(fp_line
			(start 0.12065 -0.3048)
			(end 0.67945 -0.3048)
			(stroke
				(width 0.1)
				(type default)
			)
			(layer "F.Fab")
		)
		(fp_line
			(start 0.12065 -0.2794)
			(end 0.12065 -0.3048)
			(stroke
				(width 0.1)
				(type default)
			)
			(layer "F.Fab")
		)
		(fp_line
			(start -0.12065 -0.2794)
			(end 0.12065 -0.2794)
			(stroke
				(width 0.1)
				(type default)
			)
			(layer "F.Fab")
		)
		(fp_line
			(start 0.120396 0.2794)
			(end -0.12065 0.2794)
			(stroke
				(width 0.1)
				(type default)
			)
			(layer "F.Fab")
		)
		(fp_line
			(start -0.12065 0.2794)
			(end -0.12065 0.3048)
			(stroke
				(width 0.1)
				(type default)
			)
			(layer "F.Fab")
		)
		(fp_line
			(start 0.67945 0.3048)
			(end 0.120396 0.3048)
			(stroke
				(width 0.1)
				(type default)
			)
			(layer "F.Fab")
		)
		(fp_line
			(start 0.120396 0.3048)
			(end 0.120396 0.2794)
			(stroke
				(width 0.1)
				(type default)
			)
			(layer "F.Fab")
		)
		(fp_line
			(start -0.12065 0.3048)
			(end -0.67945 0.3048)
			(stroke
				(width 0.1)
				(type default)
			)
			(layer "F.Fab")
		)
		(fp_line
			(start -0.67945 0.3048)
			(end -0.67945 -0.305054)
			(stroke
				(width 0.1)
				(type default)
			)
			(layer "F.Fab")
		)
		(pad "1" smd circle
			(at -0.40005 0 90)
			(size 0 0)
			(layers "F.Cu" "F.Mask" "F.Paste")
			(net "PVDDCR_CPU1_P0_VCC")
		)
		(pad "2" smd circle
			(at 0.40005 0 90)
			(size 0 0)
			(layers "F.Cu" "F.Mask" "F.Paste")
			(net "P3V3_AUX")
		)
	)
	(footprint ""
		(layer "F.Cu")
		(at 34.325306 19.444716 -90)
		(property "Reference" "U26_BP"
			(at 0 0 270)
			(layer "F.SilkS")
			(hide yes)
			(effects
				(font
					(size 1.27 1.27)
				)
			)
		)
		(property "Value" ""
			(at 0 0 270)
			(layer "F.Fab")
			(effects
				(font
					(size 1.27 1.27)
				)
			)
		)
		(duplicate_pad_numbers_are_jumpers no)
		(pad "1" smd circle
			(at 0 0 270)
			(size 0.762 0.762)
			(layers "F.Cu" "F.Mask" "F.Paste")
			(net "Net_10787")
		)
	)
	(footprint ""
		(layer "F.Cu")
		(at 109.165136 -123.604274 -90)
		(property "Reference" "Q27"
			(at -0.13208 1.599438 90)
			(unlocked yes)
			(layer "F.SilkS")
			(effects
				(font
					(size 0.7874 0.5842)
					(thickness 0.1524)
				)
			)
		)
		(property "Value" ""
			(at 0 0 270)
			(layer "F.Fab")
			(effects
				(font
					(size 1.27 1.27)
				)
			)
		)
		(duplicate_pad_numbers_are_jumpers no)
		(fp_line
			(start -1.7018 1.100074)
			(end -1.7018 -1.100074)
			(stroke
				(width 0.1524)
				(type default)
			)
			(layer "F.SilkS")
		)
		(fp_line
			(start 1.7018 1.100074)
			(end -1.7018 1.100074)
			(stroke
				(width 0.1524)
				(type default)
			)
			(layer "F.SilkS")
		)
		(fp_line
			(start -1.7018 -1.100074)
			(end 1.7018 -1.100074)
			(stroke
				(width 0.1524)
				(type default)
			)
			(layer "F.SilkS")
		)
		(fp_line
			(start 1.7018 -1.100074)
			(end 1.7018 1.100074)
			(stroke
				(width 0.1524)
				(type default)
			)
			(layer "F.SilkS")
		)
		(fp_poly
			(pts
				(xy -2.313686 -0.705866) (xy -2.867406 -0.409194) (xy -2.867406 -1.034034)
			)
			(stroke
				(width 0)
				(type default)
			)
			(fill yes)
			(layer "F.SilkS")
		)
		(fp_line
			(start -0.670052 1.100074)
			(end -0.670052 0.8001)
			(stroke
				(width 0.1)
				(type default)
			)
			(layer "F.Fab")
		)
		(fp_line
			(start 0.670052 1.100074)
			(end -0.670052 1.100074)
			(stroke
				(width 0.1)
				(type default)
			)
			(layer "F.Fab")
		)
		(fp_line
			(start -1.100074 0.8001)
			(end -1.100074 -0.8001)
			(stroke
				(width 0.1)
				(type default)
			)
			(layer "F.Fab")
		)
		(fp_line
			(start -0.670052 0.8001)
			(end -1.100074 0.8001)
			(stroke
				(width 0.1)
				(type default)
			)
			(layer "F.Fab")
		)
		(fp_line
			(start -0.670052 0.8001)
			(end -0.670052 -0.8001)
			(stroke
				(width 0.1)
				(type default)
			)
			(layer "F.Fab")
		)
		(fp_line
			(start 0.670052 0.8001)
			(end 0.670052 1.100074)
			(stroke
				(width 0.1)
				(type default)
			)
			(layer "F.Fab")
		)
		(fp_line
			(start 1.100074 0.8001)
			(end 0.670052 0.8001)
			(stroke
				(width 0.1)
				(type default)
			)
			(layer "F.Fab")
		)
		(fp_line
			(start -1.100074 -0.8001)
			(end -0.670052 -0.8001)
			(stroke
				(width 0.1)
				(type default)
			)
			(layer "F.Fab")
		)
		(fp_line
			(start -0.670052 -0.8001)
			(end -0.670052 -1.100074)
			(stroke
				(width 0.1)
				(type default)
			)
			(layer "F.Fab")
		)
		(fp_line
			(start 0.670052 -0.8001)
			(end 0.670052 0.8001)
			(stroke
				(width 0.1)
				(type default)
			)
			(layer "F.Fab")
		)
		(fp_line
			(start 0.670052 -0.8001)
			(end 1.100074 -0.8001)
			(stroke
				(width 0.1)
				(type default)
			)
			(layer "F.Fab")
		)
		(fp_line
			(start 1.100074 -0.8001)
			(end 1.100074 0.8001)
			(stroke
				(width 0.1)
				(type default)
			)
			(layer "F.Fab")
		)
		(fp_line
			(start -0.670052 -1.100074)
			(end 0.670052 -1.100074)
			(stroke
				(width 0.1)
				(type default)
			)
			(layer "F.Fab")
		)
		(fp_line
			(start 0.670052 -1.100074)
			(end 0.670052 -0.8001)
			(stroke
				(width 0.1)
				(type default)
			)
			(layer "F.Fab")
		)
		(fp_poly
			(pts
				(xy -2.33172 -0.338328) (xy -2.33172 -0.963168) (xy -1.778 -0.635)
			)
			(stroke
				(width 0)
				(type default)
			)
			(fill yes)
			(layer "F.Fab")
		)
		(pad "1" smd rect
			(at -0.937514 -0.649986)
			(size 0.3048 1.2446)
			(layers "F.Cu" "F.Mask" "F.Paste")
			(net "GND")
		)
		(pad "2" smd rect
			(at -0.937514 0)
			(size 0.3048 1.2446)
			(layers "F.Cu" "F.Mask" "F.Paste")
			(net "PWRGD_P3V3_EN")
		)
		(pad "3" smd rect
			(at -0.937514 0.649986)
			(size 0.3048 1.2446)
			(layers "F.Cu" "F.Mask" "F.Paste")
			(net "PWRGD_P3V3_R1")
		)
		(pad "4" smd rect
			(at 0.937514 0.649986)
			(size 0.3048 1.2446)
			(layers "F.Cu" "F.Mask" "F.Paste")
			(net "GND")
		)
		(pad "5" smd rect
			(at 0.937514 0)
			(size 0.3048 1.2446)
			(layers "F.Cu" "F.Mask" "F.Paste")
			(net "PWRGD_P3V3_EN_N")
		)
		(pad "6" smd rect
			(at 0.937514 -0.649986)
			(size 0.3048 1.2446)
			(layers "F.Cu" "F.Mask" "F.Paste")
			(net "PWRGD_P3V3_EN_N")
		)
	)
)
